# Data Center RDIMM DDR4 Tester — KiCad project settings (.kicad_pro: net classes, design rules, text variables)
{
  "board": {
    "3dviewports": [],
    "design_settings": {
      "defaults": {
        "board_outline_line_width": 0.09999999999999999,
        "copper_line_width": 0.19999999999999998,
        "copper_text_italic": false,
        "copper_text_size_h": 1.5,
        "copper_text_size_v": 1.5,
        "copper_text_thickness": 0.3,
        "copper_text_upright": false,
        "courtyard_line_width": 0.049999999999999996,
        "dimension_precision": 4,
        "dimension_units": 3,
        "dimensions": {
          "arrow_length": 1270000,
          "extension_offset": 500000,
          "keep_text_aligned": true,
          "suppress_zeroes": false,
          "text_position": 0,
          "units_format": 1
        },
        "fab_line_width": 0.09999999999999999,
        "fab_text_italic": false,
        "fab_text_size_h": 1.0,
        "fab_text_size_v": 1.0,
        "fab_text_thickness": 0.15,
        "fab_text_upright": false,
        "other_line_width": 0.09999999999999999,
        "other_text_italic": false,
        "other_text_size_h": 1.0,
        "other_text_size_v": 1.0,
        "other_text_thickness": 0.15,
        "other_text_upright": false,
        "pads": {
          "drill": 0.0,
          "height": 0.64,
          "width": 0.59
        },
        "silk_line_width": 0.15,
        "silk_text_italic": false,
        "silk_text_size_h": 0.7,
        "silk_text_size_v": 0.7,
        "silk_text_thickness": 0.15,
        "silk_text_upright": false,
        "zones": {
          "45_degree_only": false,
          "min_clearance": 0.125
        }
      },
      "diff_pair_dimensions": [
        {
          "gap": 0.0,
          "via_gap": 0.0,
          "width": 0.0
        }
      ],
      "drc_exclusions": [],
      "meta": {
        "filename": "board_design_settings.json",
        "version": 2
      },
      "rule_severities": {
        "annular_width": "error",
        "clearance": "error",
        "connection_width": "warning",
        "copper_edge_clearance": "error",
        "copper_sliver": "warning",
        "courtyards_overlap": "warning",
        "diff_pair_gap_out_of_range": "error",
        "diff_pair_uncoupled_length_too_long": "error",
        "drill_out_of_range": "error",
        "duplicate_footprints": "warning",
        "extra_footprint": "warning",
        "footprint": "error",
        "footprint_type_mismatch": "ignore",
        "hole_clearance": "error",
        "hole_near_hole": "error",
        "invalid_outline": "error",
        "isolated_copper": "warning",
        "item_on_disabled_layer": "error",
        "items_not_allowed": "error",
        "length_out_of_range": "error",
        "lib_footprint_issues": "warning",
        "lib_footprint_mismatch": "warning",
        "malformed_courtyard": "ignore",
        "microvia_drill_out_of_range": "error",
        "missing_courtyard": "ignore",
        "missing_footprint": "warning",
        "net_conflict": "warning",
        "npth_inside_courtyard": "ignore",
        "padstack": "error",
        "pth_inside_courtyard": "ignore",
        "shorting_items": "error",
        "silk_edge_clearance": "ignore",
        "silk_over_copper": "ignore",
        "silk_overlap": "warning",
        "skew_out_of_range": "error",
        "solder_mask_bridge": "error",
        "starved_thermal": "error",
        "text_height": "warning",
        "text_thickness": "warning",
        "through_hole_pad_without_hole": "error",
        "too_many_vias": "error",
        "track_dangling": "warning",
        "track_width": "error",
        "tracks_crossing": "error",
        "unconnected_items": "error",
        "unresolved_variable": "error",
        "via_dangling": "warning",
        "zones_intersect": "error"
      },
      "rule_severitieslegacy_courtyards_overlap": true,
      "rule_severitieslegacy_no_courtyard_defined": false,
      "rules": {
        "allow_blind_buried_vias": true,
        "allow_microvias": false,
        "max_error": 0.005,
        "min_clearance": 0.0,
        "min_connection": 0.0,
        "min_copper_edge_clearance": 0.049999999999999996,
        "min_hole_clearance": 0.15,
        "min_hole_to_hole": 0.25,
        "min_microvia_diameter": 0.19999999999999998,
        "min_microvia_drill": 0.09999999999999999,
        "min_resolved_spokes": 1,
        "min_silk_clearance": 0.0,
        "min_text_height": 0.7,
        "min_text_thickness": 0.08,
        "min_through_hole_diameter": 0.15,
        "min_track_width": 0.06999999999999999,
        "min_via_annular_width": 0.049999999999999996,
        "min_via_diameter": 0.44999999999999996,
        "solder_mask_to_copper_clearance": 0.0,
        "use_height_for_length_calcs": true
      },
      "teardrop_options": [
        {
          "td_allow_use_two_tracks": true,
          "td_curve_segcount": 5,
          "td_on_pad_in_zone": false,
          "td_onpadsmd": true,
          "td_onroundshapesonly": false,
          "td_ontrackend": false,
          "td_onviapad": true
        }
      ],
      "teardrop_parameters": [
        {
          "td_curve_segcount": 0,
          "td_height_ratio": 1.0,
          "td_length_ratio": 0.5,
          "td_maxheight": 2.0,
          "td_maxlen": 1.0,
          "td_target_name": "td_round_shape",
          "td_width_to_size_filter_ratio": 0.9
        },
        {
          "td_curve_segcount": 0,
          "td_height_ratio": 1.0,
          "td_length_ratio": 0.5,
          "td_maxheight": 2.0,
          "td_maxlen": 1.0,
          "td_target_name": "td_rect_shape",
          "td_width_to_size_filter_ratio": 0.9
        },
        {
          "td_curve_segcount": 0,
          "td_height_ratio": 1.0,
          "td_length_ratio": 0.5,
          "td_maxheight": 2.0,
          "td_maxlen": 1.0,
          "td_target_name": "td_track_end",
          "td_width_to_size_filter_ratio": 0.9
        }
      ],
      "track_widths": [
        0.0,
        0.1,
        0.11,
        0.127,
        0.15,
        0.2,
        0.3,
        0.4,
        1.0
      ],
      "via_dimensions": [
        {
          "diameter": 0.0,
          "drill": 0.0
        },
        {
          "diameter": 0.5,
          "drill": 0.2
        }
      ],
      "zones_allow_external_fillets": true,
      "zones_use_no_outline": true
    },
    "layer_presets": [],
    "viewports": []
  },
  "boards": [],
  "cvpcb": {
    "equivalence_files": []
  },
  "erc": {
    "erc_exclusions": [],
    "meta": {
      "version": 0
    },
    "pin_map": [
      [
        0,
        0,
        0,
        0,
        0,
        0,
        1,
        0,
        0,
        0,
        0,
        2
      ],
      [
        0,
        2,
        0,
        1,
        0,
        0,
        1,
        0,
        2,
        2,
        2,
        2
      ],
      [
        0,
        0,
        0,
        0,
        0,
        0,
        1,
        0,
        1,
        0,
        1,
        2
      ],
      [
        0,
        1,
        0,
        0,
        0,
        0,
        1,
        1,
        2,
        1,
        1,
        2
      ],
      [
        0,
        0,
        0,
        0,
        0,
        0,
        1,
        0,
        0,
        0,
        0,
        2
      ],
      [
        0,
        0,
        0,
        0,
        0,
        0,
        0,
        0,
        0,
        0,
        0,
        2
      ],
      [
        1,
        1,
        1,
        1,
        1,
        0,
        1,
        1,
        1,
        1,
        1,
        2
      ],
      [
        0,
        0,
        0,
        1,
        0,
        0,
        1,
        0,
        0,
        0,
        0,
        2
      ],
      [
        0,
        2,
        1,
        2,
        0,
        0,
        1,
        0,
        2,
        2,
        2,
        2
      ],
      [
        0,
        2,
        0,
        1,
        0,
        0,
        1,
        0,
        2,
        0,
        0,
        2
      ],
      [
        0,
        2,
        1,
        1,
        0,
        0,
        1,
        0,
        2,
        0,
        0,
        2
      ],
      [
        2,
        2,
        2,
        2,
        2,
        2,
        2,
        2,
        2,
        2,
        2,
        2
      ]
    ],
    "rule_severities": {
      "bus_definition_conflict": "error",
      "bus_entry_needed": "error",
      "bus_to_bus_conflict": "error",
      "bus_to_net_conflict": "error",
      "conflicting_netclasses": "error",
      "different_unit_footprint": "error",
      "different_unit_net": "error",
      "duplicate_reference": "error",
      "duplicate_sheet_names": "error",
      "endpoint_off_grid": "warning",
      "extra_units": "error",
      "global_label_dangling": "ignore",
      "hier_label_mismatch": "error",
      "label_dangling": "error",
      "lib_symbol_issues": "warning",
      "missing_bidi_pin": "warning",
      "missing_input_pin": "warning",
      "missing_power_pin": "error",
      "missing_unit": "warning",
      "multiple_net_names": "warning",
      "net_not_bus_member": "warning",
      "no_connect_connected": "ignore",
      "no_connect_dangling": "warning",
      "pin_not_connected": "error",
      "pin_not_driven": "error",
      "pin_to_pin": "ignore",
      "power_pin_not_driven": "error",
      "similar_labels": "warning",
      "simulation_model_issue": "ignore",
      "unannotated": "error",
      "unit_value_mismatch": "error",
      "unresolved_variable": "error",
      "wire_dangling": "error"
    }
  },
  "libraries": {
    "pinned_footprint_libs": [],
    "pinned_symbol_libs": []
  },
  "meta": {
    "filename": "data-center-rdimm-ddr4-tester.kicad_pro",
    "version": 1
  },
  "net_settings": {
    "classes": [
      {
        "bus_width": 12,
        "clearance": 0.09,
        "diff_pair_gap": 0.15,
        "diff_pair_via_gap": 0.25,
        "diff_pair_width": 0.1,
        "line_style": 0,
        "microvia_diameter": 0.3,
        "microvia_drill": 0.1,
        "name": "Default",
        "pcb_color": "rgba(0, 0, 0, 0.000)",
        "schematic_color": "rgba(0, 0, 0, 0.000)",
        "track_width": 0.12,
        "via_diameter": 0.5,
        "via_drill": 0.2,
        "wire_width": 6
      },
      {
        "bus_width": 12,
        "clearance": 0.1,
        "diff_pair_gap": 0.2,
        "diff_pair_via_gap": 0.25,
        "diff_pair_width": 0.1,
        "line_style": 0,
        "microvia_diameter": 0.3,
        "microvia_drill": 0.1,
        "name": "100Ohm-diff",
        "pcb_color": "rgba(0, 0, 0, 0.000)",
        "schematic_color": "rgba(0, 0, 0, 0.000)",
        "track_width": 0.1,
        "via_diameter": 0.5,
        "via_drill": 0.2,
        "wire_width": 6
      },
      {
        "bus_width": 12,
        "clearance": 0.1,
        "diff_pair_gap": 0.15,
        "diff_pair_via_gap": 0.25,
        "diff_pair_width": 0.1,
        "line_style": 0,
        "microvia_diameter": 0.3,
        "microvia_drill": 0.1,
        "name": "40Ohm-se_DQ",
        "pcb_color": "rgb(255, 0, 214)",
        "schematic_color": "rgba(0, 0, 0, 0.000)",
        "track_width": 0.2,
        "via_diameter": 0.5,
        "via_drill": 0.2,
        "wire_width": 6
      },
      {
        "bus_width": 12,
        "clearance": 0.1,
        "diff_pair_gap": 0.15,
        "diff_pair_via_gap": 0.25,
        "diff_pair_width": 0.1,
        "line_style": 0,
        "microvia_diameter": 0.3,
        "microvia_drill": 0.1,
        "name": "50Ohm-se",
        "pcb_color": "rgba(0, 0, 0, 0.000)",
        "schematic_color": "rgba(0, 0, 0, 0.000)",
        "track_width": 0.1,
        "via_diameter": 0.5,
        "via_drill": 0.2,
        "wire_width": 6
      },
      {
        "bus_width": 12,
        "clearance": 0.1,
        "diff_pair_gap": 0.1,
        "diff_pair_via_gap": 0.25,
        "diff_pair_width": 0.11,
        "line_style": 0,
        "microvia_diameter": 0.3,
        "microvia_drill": 0.1,
        "name": "80Ohm-diff_DQS",
        "pcb_color": "rgb(0, 255, 0)",
        "schematic_color": "rgba(0, 0, 0, 0.000)",
        "track_width": 0.1,
        "via_diameter": 0.5,
        "via_drill": 0.2,
        "wire_width": 6
      },
      {
        "bus_width": 12,
        "clearance": 0.09,
        "diff_pair_gap": 0.102,
        "diff_pair_via_gap": 0.25,
        "diff_pair_width": 0.11,
        "line_style": 0,
        "microvia_diameter": 0.0,
        "microvia_drill": 0.0,
        "name": "85Ohm-diff_PCIe",
        "pcb_color": "rgba(0, 0, 0, 0.000)",
        "schematic_color": "rgba(0, 0, 0, 0.000)",
        "track_width": 0.11,
        "via_diameter": 0.5,
        "via_drill": 0.2,
        "wire_width": 6
      },
      {
        "bus_width": 12,
        "clearance": 0.1,
        "diff_pair_gap": 0.2,
        "diff_pair_via_gap": 0.25,
        "diff_pair_width": 0.1,
        "line_style": 0,
        "microvia_diameter": 0.3,
        "microvia_drill": 0.1,
        "name": "90Ohm-diff_FMC",
        "pcb_color": "rgba(0, 0, 0, 0.000)",
        "schematic_color": "rgba(0, 0, 0, 0.000)",
        "track_width": 0.1,
        "via_diameter": 0.5,
        "via_drill": 0.2,
        "wire_width": 6
      },
      {
        "bus_width": 12,
        "clearance": 0.13,
        "diff_pair_gap": 0.12,
        "diff_pair_via_gap": 0.25,
        "diff_pair_width": 0.1,
        "line_style": 0,
        "microvia_diameter": 0.3,
        "microvia_drill": 0.1,
        "name": "90Ohm-diff_USB",
        "pcb_color": "rgba(0, 0, 0, 0.000)",
        "schematic_color": "rgba(0, 0, 0, 0.000)",
        "track_width": 0.15,
        "via_diameter": 0.5,
        "via_drill": 0.2,
        "wire_width": 6
      },
      {
        "bus_width": 12,
        "clearance": 0.33,
        "diff_pair_gap": 0.15,
        "diff_pair_via_gap": 0.25,
        "diff_pair_width": 0.1,
        "line_style": 0,
        "microvia_diameter": 0.3,
        "microvia_drill": 0.1,
        "name": "POE",
        "pcb_color": "rgba(0, 0, 0, 0.000)",
        "schematic_color": "rgba(0, 0, 0, 0.000)",
        "track_width": 0.1,
        "via_diameter": 0.5,
        "via_drill": 0.2,
        "wire_width": 6
      }
    ],
    "meta": {
      "version": 3
    },
    "net_colors": null,
    "netclass_assignments": null,
    "netclass_patterns": []
  },
  "pcbnew": {
    "last_paths": {
      "gencad": "",
      "idf": "",
      "netlist": "",
      "specctra_dsn": "",
      "step": "data-center-rdimm-ddr4-tester.step",
      "vrml": "data-center-rdimm-ddr4-tester.wrl"
    },
    "page_layout_descr_file": ""
  },
  "schematic": {
    "annotate_start_num": 0,
    "drawing": {
      "dashed_lines_dash_length_ratio": 12.0,
      "dashed_lines_gap_length_ratio": 3.0,
      "default_line_thickness": 6.0,
      "default_text_size": 50.0,
      "field_names": [],
      "intersheets_ref_own_page": false,
      "intersheets_ref_prefix": "",
      "intersheets_ref_short": false,
      "intersheets_ref_show": false,
      "intersheets_ref_suffix": "",
      "junction_size_choice": 3,
      "label_size_ratio": 0.25,
      "pin_symbol_size": 0.0,
      "text_offset_ratio": 0.08
    },
    "legacy_lib_dir": "",
    "legacy_lib_list": [],
    "meta": {
      "version": 1
    },
    "net_format_name": "Pcbnew",
    "ngspice": {
      "fix_include_paths": true,
      "fix_passive_vals": false,
      "meta": {
        "version": 0
      },
      "model_mode": 0,
      "workbook_filename": ""
    },
    "page_layout_descr_file": "",
    "plot_directory": "./doc",
    "spice_adjust_passive_values": false,
    "spice_current_sheet_as_root": false,
    "spice_external_command": "spice \"%I\"",
    "spice_model_current_sheet_as_root": true,
    "spice_save_all_currents": false,
    "spice_save_all_voltages": false,
    "subpart_first_id": 65,
    "subpart_id_separator": 0
  },
  "sheets": [
    [
      "",
      ""
    ],
    [
      "",
      "HyperRAM"
    ],
    [
      "",
      "Config SPI flash"
    ],
    [
      "",
      "DDR4"
    ],
    [
      "",
      "FPGA power"
    ],
    [
      "",
      "Interfaces"
    ],
    [
      "",
      "FPGA banks 12-15"
    ],
    [
      "",
      "Ethernet"
    ],
    [
      "",
      "FPGA banks 16-34"
    ],
    [
      "",
      "Supply"
    ],
    [
      "",
      "FPGA banks 115-116"
    ],
    [
      "",
      "FMC HPC"
    ]
  ],
  "text_variables": {}
}
